FILE_TYPE = CONNECTIVITY;
{Allegro Design Entry HDL 16.6-p007 (v16-6-112F) 10/10/2012}
"PAGE_NUMBER" = 194;
0"NC";
1"GND\g";
2"PVCCIOMCP_CPU0\g";
3"GND\g";
4"GND\g";
5"P12V_STBY\g";
6"P3V3_STBY\g";
7"P5V_STBY\g";
8"GND\g";
9"PVCCMCP_CPU0\g";
10"P1V8_MCP_CPU0\g";
11"P1V8_MCP_CPU0\g";
12"P1V8_MCP_CPU0\g";
13"PVCCIOMCP_CPU0\g";
14"GND\g";
15"PVCCIO_CPU0\g";
16"GND\g";
17"P3V3\g";
18"GND\g";
19"PVCCMCP_CPU0\g"VOLTAGE"1.2V";
20"GND\g";
21"GND\g";
22"GND\g";
23"PVCCMCP_CPU0\g";
24"PVCCMCP_CPU0\g";
25"GND\g";
26"PVCCIOMCP_CPU0\g";
27"VR_PVCCIOMCP_CPU0_XADDR1";
28"VR_PVCCMCP_CPU0_XADDR2";
29"VSENSE_PVCCIOMCP_CPU0_SKT_VSEN";
30"VSENSE_PVCCIOMCP_CPU0_SKT_VRTN";
31"FM_CPU0_VRM_322M_156M_OSC_EN";
32"SVID_CLK0_CPU0_R";
33"SMB_VR_STBY_LVC3_SCL";
34"SMB_VR_STBY_LVC3_SDA";
35"FM_PVCCIOMCP_CPU0_EN";
36"PWRGD_PVCCIOMCP_CPU0";
37"PWRGD_P1V8MCP_CPU0";
38"FM_P1V8MCP_CPU0_EN";
39"SVID_ALERT0_CPU0_R_N";
40"PWRGD_PVCCMCP_CPU0";
41"FM_PVCCMCP_CPU0_EN";
42"SVID_DIO1_CPU0_R";
43"SVID_CLK1_CPU0_R";
44"SVID_DIO0_CPU0_R";
45"SVID_ALERT1_CPU0_R_N";
46"CLK_322M_156M_CPU0_OSC_VRM_DP";
47"CLK_322M_156M_CPU0_OSC_VRM_DN";
48"VSENSE_PVCCMCP_CPU0_SKT_VSEN";
49"VSENSE_PVCCMCP_CPU0_SKT_VRTN";
50"VSENSE_P1V8MCP_CPU0_SKT_VRTN";
51"VSENSE_P1V8MCP_CPU0_SKT_VSEN";
%"GND"
"1","(-1450,2875)","0","mstr_symbols","I100";
;
HDL_POWER"GND"
ROOM"PVSA_CPU0_DECAP_VR"
BODY_TYPE"PLUMBING"
SIZE"1B"
BOM_COST"PROC_VRD_VCCIN_CPU0"
CDS_LIB"mstr_symbols"
VOLTAGE"0";
"A\NAC"1;
%"CAPP"
"1","(-1450,3150)","0","mstr_discrete","I101";
;
CDS_SEC"1"
ROOM"P0V95_MCP_CPU0_DECAP_VR"
CDS_LOCATION"C3N14"
SEC"1"
BOM_COST"PROC_VRD_VCCIN_CPU0"
CDS_LIB"mstr_discrete"
SEC_TYPE"3018"
VOLTAGE"2.5V"
MATERIAL"ALUM"
PACK_TYPE"3018"
TOLERANCE"20%"
VALUE"470UF"
PART_NUMBER"699013-049"
LOCATION"C3N14";
"B"
$PN"2"1;
"A"
$PN"1"2;
%"VCC_CORE"
"1","(-1450,3425)","0","mstr_symbols","I102";
;
CDS_LIB"mstr_symbols"
VOLTAGE"+0.95"
HDL_POWER"PVCCIOMCP_CPU0";
"A"2;
%"GND"
"1","(-7375,1225)","0","mstr_symbols","I110";
;
HDL_POWER"GND"
BODY_TYPE"PLUMBING"
CDS_LIB"mstr_symbols"
SIZE"1B"
VOLTAGE"0.0V";
"A\NAC"3;
%"GND"
"1","(-7225,675)","0","mstr_symbols","I111";
;
HDL_POWER"GND"
BODY_TYPE"PLUMBING"
SIZE"1B"
CDS_LIB"mstr_symbols"
VOLTAGE"0.0V";
"A\NAC"4;
%"P12V_STBY"
"1","(-7175,4075)","0","mstr_symbols","I119";
;
HDL_POWER"P12V_STBY"
BODY_TYPE"PLUMBING"
CDS_LIB"mstr_symbols"
SIZE"1B"
VOLTAGE"12.0V";
"G\NAC"5;
%"P3V3_STBY"
"1","(-5725,3900)","0","mstr_symbols","I120";
;
HDL_POWER"P3V3_STBY"
BODY_TYPE"PLUMBING"
CDS_LIB"mstr_symbols"
SIZE"1B"
VOLTAGE"+3.3V";
"G\NAC"6;
%"P5V_STBY"
"1","(-5775,3200)","0","mstr_symbols","I121";
;
HDL_POWER"P5V_STBY"
BODY_TYPE"PLUMBING"
CDS_LIB"mstr_symbols"
SIZE"1B"
VOLTAGE"+5.0V";
"G\NAC"7;
%"GND"
"1","(-5350,1525)","0","mstr_symbols","I127";
;
HDL_POWER"GND"
BODY_TYPE"PLUMBING"
SIZE"1B"
CDS_LIB"mstr_symbols"
VOLTAGE"0.0V";
"A\NAC"8;
%"VCC_CORE"
"1","(-3900,3925)","0","mstr_symbols","I130";
;
ROOM"PVMCP_FPGA_CPU0_VR"
CDS_LIB"mstr_symbols"
BOM_COST"PVMCP_FPGA_CPU0_VR"
HDL_POWER"PVCCMCP_CPU0";
"A"9;
%"VCC_CORE"
"1","(-4175,4050)","0","mstr_symbols","I141";
;
CDS_LIB"mstr_symbols"
HDL_POWER"P1V8_MCP_CPU0";
"A"10;
%"VCC_CORE"
"1","(-1450,1350)","0","mstr_symbols","I142";
;
CDS_LIB"mstr_symbols"
HDL_POWER"P1V8_MCP_CPU0";
"A"11;
%"VCC_CORE"
"1","(-900,1475)","0","mstr_symbols","I143";
;
CDS_LIB"mstr_symbols"
HDL_POWER"P1V8_MCP_CPU0";
"A"12;
%"VCC_CORE"
"1","(-5450,2575)","0","mstr_symbols","I144";
;
CDS_LIB"mstr_symbols"
VOLTAGE"+0.95"
HDL_POWER"PVCCIOMCP_CPU0";
"A"13;
%"CAP_A"
"1","(-1450,1100)","0","dev_discrete","I149";
;
SEC"1"
SEC_TYPE"0603V"
CDS_SEC"1"
CDS_LIB"dev_discrete"
CDS_LOCATION"C3T1"
MATERIAL"X5R"
VOLTAGE"4V"
PACK_TYPE"0603V"
TOLERANCE"20%"
VALUE"47UF"
PART_NUMBER"602433-106"
LOCATION"C3T1";
"B"
$PN"2"18;
"A"
$PN"1"11;
%"CAP_A"
"1","(-1750,1075)","0","dev_discrete","I150";
;
SEC"1"
SEC_TYPE"0603V"
CDS_SEC"1"
CDS_LIB"dev_discrete"
CDS_LOCATION"C3T2"
MATERIAL"X5R"
VOLTAGE"4V"
PACK_TYPE"0603V"
TOLERANCE"20%"
VALUE"47UF"
PART_NUMBER"602433-106"
LOCATION"C3T2";
"B"
$PN"2"18;
"A"
$PN"1"11;
%"GND"
"1","(-900,775)","0","mstr_symbols","I151";
;
HDL_POWER"GND"
BODY_TYPE"PLUMBING"
CDS_LIB"mstr_symbols"
SIZE"1B"
VOLTAGE"0";
"A\NAC"14;
%"PVCCIO_CPU0"
"1","(-7425,3900)","0","mstr_symbols","I154";
;
HDL_POWER"PVCCIO_CPU0"
BODY_TYPE"PLUMBING"
CDS_LIB"mstr_symbols"
VOLTAGE"1.1V";
"G\NAC"15;
%"RES"
"2","(-7825,100)","0","mstr_discrete","I155";
;
CDS_SEC"1"
CDS_LOCATION"R7C24"
ROOM"PVCCIN_CPU1_VR"
SEC"1"
CDS_LIB"mstr_discrete"
SEC_TYPE"0402"
WATTAGE"1/16W"
MATERIAL"CHIP"
PACK_TYPE"0402"
TOLERANCE"1%"
VALUE"4.02K"
PART_NUMBER"G21796-082"
LOCATION"R7C24";
"A"
$PN"1"28;
"B"
$PN"2"16;
%"RES"
"2","(-8175,125)","0","mstr_discrete","I156";
;
CDS_SEC"1"
CDS_LOCATION"R3N29"
ROOM"VDDQ_ABC_PWR_VR"
SEC"1"
CDS_LIB"mstr_discrete"
SEC_TYPE"0402"
WATTAGE"1/16W"
MATERIAL"CHIP"
PACK_TYPE"0402"
TOLERANCE"1.0%"
VALUE"16K"
PART_NUMBER"G21796-317"
LOCATION"R3N29";
"A"
$PN"1"27;
"B"
$PN"2"16;
%"GND"
"1","(-7975,-225)","0","mstr_symbols","I157";
;
HDL_POWER"GND"
BODY_TYPE"PLUMBING"
SIZE"1B"
CDS_LIB"mstr_symbols"
VOLTAGE"0.0V";
"A\NAC"16;
%"CAP_A"
"1","(-900,1075)","2","dev_discrete","I16";
;
ROOM"P1V8_MCP_CPU0"
SEC"1"
SEC_TYPE"0402V"
CDS_SEC"1"
CDS_LIB"dev_discrete"
CDS_LOCATION"C4T1"
MATERIAL"X6S"
VOLTAGE"6.3V"
PACK_TYPE"0402V"
TOLERANCE"10%"
VALUE"1.0UF"
PART_NUMBER"D97712-004"
LOCATION"C4T1";
"B"
$PN"2"14;
"A"
$PN"1"12;
%"P3V3"
"1","(-7525,3800)","0","mstr_symbols","I170";
;
HDL_POWER"P3V3"
BODY_TYPE"PLUMBING"
SIZE"1B"
CDS_LIB"mstr_symbols"
VOLTAGE"+3.3V";
"G\NAC"17;
%"GND"
"1","(-1450,750)","0","mstr_symbols","I28";
;
HDL_POWER"GND"
BODY_TYPE"PLUMBING"
CDS_LIB"mstr_symbols"
SIZE"1B"
VOLTAGE"0";
"A\NAC"18;
%"CAPP"
"1","(-850,2275)","0","mstr_discrete","I29";
;
CDS_SEC"1"
ROOM"PVMCP_MCP_CPU0_VR"
CDS_LOCATION"C4R1"
SEC"1"
SEC_TYPE"3018"
BOM_COST"PVMCP_MCP_CPU0_VR"
CDS_LIB"mstr_discrete"
VOLTAGE"2.5V"
MATERIAL"ALUM"
PACK_TYPE"3018"
TOLERANCE"20%"
VALUE"470UF"
PART_NUMBER"699013-049"
LOCATION"C4R1";
"B"
$PN"2"20;
"A"
$PN"1"19;
%"VCC_CORE"
"1","(-1275,2600)","0","mstr_symbols","I30";
;
ROOM"PVMCP_FPGA_CPU0_VR"
BOM_COST"PVMCP_FPGA_CPU0_VR"
CDS_LIB"mstr_symbols"
HDL_POWER"PVCCMCP_CPU0";
"A"19;
%"CAPP"
"1","(-1275,2275)","0","mstr_discrete","I31";
;
ROOM"PVMCP_MCP_CPU0_VR"
CDS_LOCATION"C3R4"
$SEC"1"
CDS_SEC"1"
BOM_COST"PVMCP_MCP_CPU0_VR"
CDS_LIB"mstr_discrete"
VOLTAGE"2.5V"
MATERIAL"ALUM"
PACK_TYPE"3018"
TOLERANCE"20%"
VALUE"470UF"
PART_NUMBER"699013-049"
LOCATION"C3R4";
"B"
$PN"2"20;
"A"
$PN"1"19;
%"GND"
"1","(-1275,1875)","0","mstr_symbols","I33";
;
HDL_POWER"GND"
ROOM"PVMCP_FPGA_CPU0_VR"
BODY_TYPE"PLUMBING"
BOM_COST"PVMCP_FPGA_CPU0_VR"
SIZE"1B"
CDS_LIB"mstr_symbols"
VOLTAGE"0.0V";
"A\NAC"20;
%"SCONN120_H61426002"
"1","(-3150,2100)","0","mstr_sconn","I55";
;
CDS_SEC"1"
CDS_LOCATION"J6E1"
SEC"1"
CDS_LIB"mstr_sconn"
SEC_TYPE"SM"
PACK_TYPE"SM"
ROOM"MCP VRM CPU0"
MATERIAL"CONN"
PART_NUMBER"H61426-002"
LOCATION"J6E1";
"IOB11"
$PN"B11"24;
"IOA1"
$PN"A1"9;
"IOB1"
$PN"B1"9;
"IOD1"
$PN"D1"51;
"IOC1"
$PN"C1"9;
"IOE1"
$PN"E1"10;
"IOF1"
$PN"F1"10;
"IOB2"
$PN"B2"9;
"IOA2"
$PN"A2"9;
"IOC2"
$PN"C2"9;
"IOD2"
$PN"D2"50;
"IOE2"
$PN"E2"10;
"IOF2"
$PN"F2"10;
"IOB3"
$PN"B3"9;
"IOA3"
$PN"A3"9;
"IOC3"
$PN"C3"9;
"IOD3"
$PN"D3"21;
"IOE3"
$PN"E3"21;
"IOF3"
$PN"F3"21;
"IOA4"
$PN"A4"48;
"IOB4"
$PN"B4"49;
"IOC4"
$PN"C4"23;
"IOD4"
$PN"D4"21;
"IOF4"
$PN"F4"21;
"IOE4"
$PN"E4"21;
"IOA5"
$PN"A5"23;
"IOB5"
$PN"B5"23;
"IOD5"
$PN"D5"21;
"IOC5"
$PN"C5"23;
"IOF5"
$PN"F5"47;
"IOE5"
$PN"E5"46;
"IOA6"
$PN"A6"23;
"IOB6"
$PN"B6"23;
"IOD6"
$PN"D6"21;
"IOC6"
$PN"C6"23;
"IOE6"
$PN"E6"21;
"IOF6"
$PN"F6"21;
"IOA7"
$PN"A7"23;
"IOC7"
$PN"C7"23;
"IOB7"
$PN"B7"23;
"IOE7"
$PN"E7"21;
"IOD7"
$PN"D7"21;
"IOF7"
$PN"F7"21;
"IOA8"
$PN"A8"23;
"IOB8"
$PN"B8"23;
"IOC8"
$PN"C8"23;
"IOD8"
$PN"D8"21;
"IOF8"
$PN"F8"21;
"IOE8"
$PN"E8"21;
"IOB9"
$PN"B9"23;
"IOA9"
$PN"A9"23;
"IOC9"
$PN"C9"23;
"IOD9"
$PN"D9"21;
"IOE9"
$PN"E9"21;
"IOF9"
$PN"F9"21;
"IOA10"
$PN"A10"23;
"IOB10"
$PN"B10"23;
"IOC10"
$PN"C10"23;
"IOE10"
$PN"E10"21;
"IOD10"
$PN"D10"21;
"IOF10"
$PN"F10"21;
"IOA11"
$PN"A11"24;
"IOC11"
$PN"C11"24;
"IOD11"
$PN"D11"22;
"IOE11"
$PN"E11"22;
"IOF11"
$PN"F11"22;
"IOA12"
$PN"A12"24;
"IOB12"
$PN"B12"24;
"IOD12"
$PN"D12"22;
"IOC12"
$PN"C12"24;
"IOF12"
$PN"F12"22;
"IOE12"
$PN"E12"22;
"IOA13"
$PN"A13"24;
"IOB13"
$PN"B13"24;
"IOC13"
$PN"C13"24;
"IOE13"
$PN"E13"22;
"IOD13"
$PN"D13"22;
"IOF13"
$PN"F13"22;
"IOA14"
$PN"A14"24;
"IOC14"
$PN"C14"24;
"IOB14"
$PN"B14"24;
"IOE14"
$PN"E14"22;
"IOD14"
$PN"D14"22;
"IOF14"
$PN"F14"22;
"IOA15"
$PN"A15"24;
"IOB15"
$PN"B15"24;
"IOC15"
$PN"C15"24;
"IOD15"
$PN"D15"22;
"IOF15"
$PN"F15"22;
"IOE15"
$PN"E15"22;
"IOA16"
$PN"A16"24;
"IOB16"
$PN"B16"24;
"IOC16"
$PN"C16"24;
"IOD16"
$PN"D16"22;
"IOE16"
$PN"E16"22;
"IOF16"
$PN"F16"22;
"IOA17"
$PN"A17"24;
"IOB17"
$PN"B17"24;
"IOC17"
$PN"C17"24;
"IOD17"
$PN"D17"22;
"IOE17"
$PN"E17"22;
"IOF17"
$PN"F17"22;
"IOA18"
$PN"A18"24;
"IOC18"
$PN"C18"24;
"IOB18"
$PN"B18"24;
"IOD18"
$PN"D18"22;
"IOE18"
$PN"E18"22;
"IOF18"
$PN"F18"22;
"IOA19"
$PN"A19"22;
"IOB19"
$PN"B19"22;
"IOD19"
$PN"D19"22;
"IOC19"
$PN"C19"22;
"IOF19"
$PN"F19"22;
"IOE19"
$PN"E19"22;
"IOB20"
$PN"B20"22;
"IOA20"
$PN"A20"22;
"IOD20"
$PN"D20"22;
"IOC20"
$PN"C20"22;
"IOE20"
$PN"E20"22;
"IOF20"
$PN"F20"22;
%"SCONN120_H61426002"
"1","(-6550,2075)","0","mstr_sconn","I56";
;
CDS_SEC"1"
CDS_LOCATION"J6B1"
SEC"1"
CDS_LIB"mstr_sconn"
SEC_TYPE"SM"
PACK_TYPE"SM"
ROOM"MCP VRM CPU0"
MATERIAL"CONN"
PART_NUMBER"H61426-002"
LOCATION"J6B1";
"IOB11"
$PN"B11"6;
"IOA1"
$PN"A1"5;
"IOB1"
$PN"B1"5;
"IOD1"
$PN"D1"17;
"IOC1"
$PN"C1"3;
"IOE1"
$PN"E1"31;
"IOF1"
$PN"F1"15;
"IOB2"
$PN"B2"5;
"IOA2"
$PN"A2"5;
"IOC2"
$PN"C2"3;
"IOD2"
$PN"D2"3;
"IOE2"
$PN"E2"3;
"IOF2"
$PN"F2"3;
"IOB3"
$PN"B3"5;
"IOA3"
$PN"A3"5;
"IOC3"
$PN"C3"3;
"IOD3"
$PN"D3"3;
"IOE3"
$PN"E3"3;
"IOF3"
$PN"F3"3;
"IOA4"
$PN"A4"5;
"IOB4"
$PN"B4"5;
"IOC4"
$PN"C4"3;
"IOD4"
$PN"D4"3;
"IOF4"
$PN"F4"3;
"IOE4"
$PN"E4"3;
"IOA5"
$PN"A5"5;
"IOB5"
$PN"B5"5;
"IOD5"
$PN"D5"3;
"IOC5"
$PN"C5"3;
"IOF5"
$PN"F5"3;
"IOE5"
$PN"E5"3;
"IOA6"
$PN"A6"5;
"IOB6"
$PN"B6"5;
"IOD6"
$PN"D6"3;
"IOC6"
$PN"C6"3;
"IOE6"
$PN"E6"3;
"IOF6"
$PN"F6"3;
"IOA7"
$PN"A7"5;
"IOC7"
$PN"C7"3;
"IOB7"
$PN"B7"5;
"IOE7"
$PN"E7"3;
"IOD7"
$PN"D7"3;
"IOF7"
$PN"F7"3;
"IOA8"
$PN"A8"5;
"IOB8"
$PN"B8"5;
"IOC8"
$PN"C8"4;
"IOD8"
$PN"D8"4;
"IOF8"
$PN"F8"30;
"IOE8"
$PN"E8"29;
"IOB9"
$PN"B9"4;
"IOA9"
$PN"A9"4;
"IOC9"
$PN"C9"4;
"IOD9"
$PN"D9"4;
"IOE9"
$PN"E9"4;
"IOF9"
$PN"F9"4;
"IOA10"
$PN"A10"4;
"IOB10"
$PN"B10"4;
"IOC10"
$PN"C10"4;
"IOE10"
$PN"E10"27;
"IOD10"
$PN"D10"4;
"IOF10"
$PN"F10"28;
"IOA11"
$PN"A11"6;
"IOC11"
$PN"C11"6;
"IOD11"
$PN"D11"8;
"IOE11"
$PN"E11"8;
"IOF11"
$PN"F11"8;
"IOA12"
$PN"A12"8;
"IOB12"
$PN"B12"8;
"IOD12"
$PN"D12"8;
"IOC12"
$PN"C12"8;
"IOF12"
$PN"F12"8;
"IOE12"
$PN"E12"8;
"IOA13"
$PN"A13"7;
"IOB13"
$PN"B13"7;
"IOC13"
$PN"C13"7;
"IOE13"
$PN"E13"8;
"IOD13"
$PN"D13"8;
"IOF13"
$PN"F13"8;
"IOA14"
$PN"A14"8;
"IOC14"
$PN"C14"8;
"IOB14"
$PN"B14"8;
"IOE14"
$PN"E14"8;
"IOD14"
$PN"D14"8;
"IOF14"
$PN"F14"8;
"IOA15"
$PN"A15"38;
"IOB15"
$PN"B15"37;
"IOC15"
$PN"C15"8;
"IOD15"
$PN"D15"13;
"IOF15"
$PN"F15"13;
"IOE15"
$PN"E15"13;
"IOA16"
$PN"A16"35;
"IOB16"
$PN"B16"36;
"IOC16"
$PN"C16"8;
"IOD16"
$PN"D16"13;
"IOE16"
$PN"E16"13;
"IOF16"
$PN"F16"13;
"IOA17"
$PN"A17"8;
"IOB17"
$PN"B17"8;
"IOC17"
$PN"C17"13;
"IOD17"
$PN"D17"13;
"IOE17"
$PN"E17"13;
"IOF17"
$PN"F17"13;
"IOA18"
$PN"A18"33;
"IOC18"
$PN"C18"13;
"IOB18"
$PN"B18"34;
"IOD18"
$PN"D18"13;
"IOE18"
$PN"E18"13;
"IOF18"
$PN"F18"13;
"IOA19"
$PN"A19"39;
"IOB19"
$PN"B19"45;
"IOD19"
$PN"D19"13;
"IOC19"
$PN"C19"13;
"IOF19"
$PN"F19"13;
"IOE19"
$PN"E19"13;
"IOB20"
$PN"B20"44;
"IOA20"
$PN"A20"32;
"IOD20"
$PN"D20"40;
"IOC20"
$PN"C20"41;
"IOE20"
$PN"E20"43;
"IOF20"
$PN"F20"42;
%"GND"
"1","(-3975,225)","0","mstr_symbols","I61";
;
HDL_POWER"GND"
BODY_TYPE"PLUMBING"
SIZE"1B"
CDS_LIB"mstr_symbols"
VOLTAGE"0.0V";
"A\NAC"21;
%"GND"
"1","(-2150,200)","0","mstr_symbols","I62";
;
HDL_POWER"GND"
BODY_TYPE"PLUMBING"
CDS_LIB"mstr_symbols"
SIZE"1B"
VOLTAGE"0.0V";
"A\NAC"22;
%"VCC_CORE"
"1","(-4925,3050)","0","mstr_symbols","I68";
;
ROOM"PVMCP_FPGA_CPU0_VR"
CDS_LIB"mstr_symbols"
BOM_COST"PVMCP_FPGA_CPU0_VR"
HDL_POWER"PVCCMCP_CPU0";
"A"23;
%"VCC_CORE"
"1","(-2300,3925)","0","mstr_symbols","I69";
;
ROOM"PVMCP_FPGA_CPU0_VR"
CDS_LIB"mstr_symbols"
BOM_COST"PVMCP_FPGA_CPU0_VR"
HDL_POWER"PVCCMCP_CPU0";
"A"24;
%"CAP_A"
"1","(-600,3250)","2","dev_discrete","I86";
;
CDS_LOCATION"C3N40"
ROOM"P0V95_MCP_CPU0"
SEC"1"
SEC_TYPE"0402V"
CDS_SEC"1"
CDS_LIB"dev_discrete"
MATERIAL"X6S"
VOLTAGE"6.3V"
PACK_TYPE"0402V"
TOLERANCE"10%"
VALUE"1.0UF"
PART_NUMBER"D97712-004"
LOCATION"C3N40";
"B"
$PN"2"25;
"A"
$PN"1"26;
%"CAP_A"
"1","(-475,1075)","2","dev_discrete","I9";
;
ROOM"P1V8_MCP_CPU0"
SEC"1"
SEC_TYPE"0402V"
CDS_SEC"1"
CDS_LIB"dev_discrete"
CDS_LOCATION"C4T2"
MATERIAL"X6S"
VOLTAGE"6.3V"
PACK_TYPE"0402V"
TOLERANCE"10%"
VALUE"1.0UF"
PART_NUMBER"D97712-004"
LOCATION"C4T2";
"B"
$PN"2"14;
"A"
$PN"1"12;
%"GND"
"1","(-1025,2900)","0","mstr_symbols","I92";
;
HDL_POWER"GND"
BODY_TYPE"PLUMBING"
CDS_LIB"mstr_symbols"
SIZE"1B"
VOLTAGE"0.0V";
"A\NAC"25;
%"VCC_CORE"
"1","(-1025,3650)","0","mstr_symbols","I95";
;
CDS_LIB"mstr_symbols"
HDL_POWER"PVCCIOMCP_CPU0";
"A"26;
%"CAP_A"
"1","(-1025,3250)","2","dev_discrete","I99";
;
CDS_LOCATION"C3M46"
ROOM"P0V95_MCP_CPU0"
SEC"1"
SEC_TYPE"0402V"
CDS_SEC"1"
CDS_LIB"dev_discrete"
MATERIAL"X6S"
VOLTAGE"6.3V"
PACK_TYPE"0402V"
TOLERANCE"10%"
VALUE"1.0UF"
PART_NUMBER"D97712-004"
LOCATION"C3M46";
"B"
$PN"2"25;
"A"
$PN"1"26;
END.
